(kicad_pcb
	(version 20260206)
	(generator "pcbnew")
	(generator_version "10.0")
	(general
		(thickness 1.6)
		(legacy_teardrops no)
	)
	(paper "A4")
	(title_block
		(title "v1-chassis-manager — T6M_CM_d_v01_1031_1645.brd")
		(comment 1 "Open CloudServer (Microsoft) / footprints 59-66 of 2512")
	)
	(layers
		(0 "F.Cu" signal "TOP")
		(4 "In1.Cu" signal "GND1")
		(6 "In2.Cu" signal "IN1")
		(8 "In3.Cu" signal "VCC1")
		(10 "In4.Cu" signal "VCC2")
		(12 "In5.Cu" signal "GND2")
		(14 "In6.Cu" signal "IN2")
		(16 "In7.Cu" signal "IN3")
		(18 "In8.Cu" signal "GND3")
		(2 "B.Cu" signal "BOTTOM")
		(9 "F.Adhes" user "F.Adhesive")
		(11 "B.Adhes" user "B.Adhesive")
		(13 "F.Paste" user "Package Geometry/Pastemask Top")
		(15 "B.Paste" user "Package Geometry/Pastemask Bottom")
		(5 "F.SilkS" user "Ref Des/Silkscreen Top")
		(7 "B.SilkS" user "Ref Des/Silkscreen Bottom")
		(1 "F.Mask" user "Board Geometry/Soldermask Top")
		(3 "B.Mask" user "Board Geometry/Soldermask Bottom")
		(17 "Dwgs.User" user "User.Drawings")
		(19 "Cmts.User" user "User.Comments")
		(21 "Eco1.User" user "User.Eco1")
		(23 "Eco2.User" user "User.Eco2")
		(25 "Edge.Cuts" user "Board Geometry/Outline")
		(27 "Margin" user)
		(31 "F.CrtYd" user "Package Geometry/Place Bound Top")
		(29 "B.CrtYd" user "Package Geometry/Place Bound Bottom")
		(35 "F.Fab" user "Ref Des/Assembly Top")
		(33 "B.Fab" user "Ref Des/Assembly Bottom")
	)
	(footprint ""
		(layer "F.Cu")
		(at 15.286228 -63.887096 -90)
		(property "Reference" "R636"
			(at -1.893824 -0.494538 90)
			(unlocked yes)
			(layer "F.SilkS")
			(effects
				(font
					(size 0.635 0.4064)
					(thickness 0.1524)
				)
				(justify left)
			)
		)
		(property "Value" ""
			(at 0 0 270)
			(layer "F.Fab")
			(effects
				(font
					(size 1.27 1.27)
				)
			)
		)
		(duplicate_pad_numbers_are_jumpers no)
		(fp_line
			(start -0.7874 0.4064)
			(end -0.7874 -0.4064)
			(stroke
				(width 0.1524)
				(type default)
			)
			(layer "F.SilkS")
		)
		(fp_line
			(start 0.7874 0.4064)
			(end -0.7874 0.4064)
			(stroke
				(width 0.1524)
				(type default)
			)
			(layer "F.SilkS")
		)
		(fp_line
			(start -0.7874 -0.4064)
			(end 0.7874 -0.4064)
			(stroke
				(width 0.1524)
				(type default)
			)
			(layer "F.SilkS")
		)
		(fp_line
			(start 0.7874 -0.4064)
			(end 0.7874 0.4064)
			(stroke
				(width 0.1524)
				(type default)
			)
			(layer "F.SilkS")
		)
		(fp_poly
			(pts
				(xy -0.508 0.2794) (xy -0.508 0.2286) (xy -0.635 0.2286) (xy -0.635 -0.254) (xy -0.5334 -0.254)
				(xy -0.5334 -0.2794) (xy 0.5334 -0.2794) (xy 0.5334 -0.254) (xy 0.635 -0.254) (xy 0.635 0.254) (xy 0.5334 0.254)
				(xy 0.5334 0.2794)
			)
			(stroke
				(width 0)
				(type default)
			)
			(fill no)
			(layer "F.CrtYd")
		)
		(pad "1" smd rect
			(at 0.40005 0 270)
			(size 0.4572 0.508)
			(layers "F.Cu" "F.Mask" "F.Paste")
			(net "I2C_VIDREAR_5V_SCL")
		)
		(pad "2" smd rect
			(at -0.40005 0 270)
			(size 0.4572 0.508)
			(layers "F.Cu" "F.Mask" "F.Paste")
			(net "CRT_DDCCLK")
		)
	)
	(footprint ""
		(layer "F.Cu")
		(at 80.540352 -143.002762)
		(property "Reference" "C835"
			(at -1.578864 1.173988 90)
			(unlocked yes)
			(layer "F.SilkS")
			(effects
				(font
					(size 0.7874 0.5842)
					(thickness 0.1524)
				)
				(justify left)
			)
		)
		(property "Value" ""
			(at 0 0 0)
			(layer "F.Fab")
			(effects
				(font
					(size 1.27 1.27)
				)
			)
		)
		(duplicate_pad_numbers_are_jumpers no)
		(fp_line
			(start -0.7874 -0.4064)
			(end 0.7874 -0.4064)
			(stroke
				(width 0.1524)
				(type default)
			)
			(layer "F.SilkS")
		)
		(fp_line
			(start -0.7874 0.4064)
			(end -0.7874 -0.4064)
			(stroke
				(width 0.1524)
				(type default)
			)
			(layer "F.SilkS")
		)
		(fp_line
			(start 0 0.381)
			(end 0 -0.381)
			(stroke
				(width 0.1524)
				(type default)
			)
			(layer "F.SilkS")
		)
		(fp_line
			(start 0.7874 -0.4064)
			(end 0.7874 0.4064)
			(stroke
				(width 0.1524)
				(type default)
			)
			(layer "F.SilkS")
		)
		(fp_line
			(start 0.7874 0.4064)
			(end -0.7874 0.4064)
			(stroke
				(width 0.1524)
				(type default)
			)
			(layer "F.SilkS")
		)
		(fp_poly
			(pts
				(xy -0.5334 0.254) (xy -0.635 0.254) (xy -0.635 0.2286) (xy -0.635 -0.254) (xy -0.5334 -0.254) (xy -0.5334 -0.2794)
				(xy 0.5334 -0.2794) (xy 0.5334 -0.254) (xy 0.635 -0.254) (xy 0.635 0.254) (xy 0.5334 0.254) (xy 0.5334 0.2794)
				(xy -0.508 0.2794) (xy -0.5334 0.2794)
			)
			(stroke
				(width 0)
				(type default)
			)
			(fill no)
			(layer "F.CrtYd")
		)
		(pad "1" smd rect
			(at 0.40005 0)
			(size 0.4572 0.508)
			(layers "F.Cu" "F.Mask" "F.Paste")
			(net "P5V_STB_NODE1")
		)
		(pad "2" smd rect
			(at -0.40005 0)
			(size 0.4572 0.508)
			(layers "F.Cu" "F.Mask" "F.Paste")
			(net "GND")
		)
	)
	(footprint ""
		(layer "F.Cu")
		(at 51.16576 -178.804824 180)
		(property "Reference" "U96"
			(at 3.339084 -132.66293 90)
			(unlocked yes)
			(layer "F.SilkS")
			(effects
				(font
					(size 0.7874 0.5842)
					(thickness 0.1524)
				)
			)
		)
		(property "Value" ""
			(at 0 0 180)
			(layer "F.Fab")
			(effects
				(font
					(size 1.27 1.27)
				)
			)
		)
		(duplicate_pad_numbers_are_jumpers no)
		(fp_line
			(start 1.651 1.905)
			(end -1.651 1.905)
			(stroke
				(width 0.1524)
				(type default)
			)
			(layer "F.SilkS")
		)
		(fp_line
			(start 1.651 -1.905)
			(end 1.651 1.905)
			(stroke
				(width 0.1524)
				(type default)
			)
			(layer "F.SilkS")
		)
		(fp_line
			(start -1.651 1.905)
			(end -1.651 -1.905)
			(stroke
				(width 0.1524)
				(type default)
			)
			(layer "F.SilkS")
		)
		(fp_line
			(start -1.651 -1.905)
			(end 1.651 -1.905)
			(stroke
				(width 0.1524)
				(type default)
			)
			(layer "F.SilkS")
		)
		(fp_poly
			(pts
				(xy -1.524 0.7112) (xy -1.524 1.7526) (xy -0.508 1.7526) (xy -0.508 0.6985) (xy 0.508 0.6985) (xy 0.508 1.7526)
				(xy 1.524 1.7526) (xy 1.524 0.6985) (xy 1.524 -0.6985) (xy 0.508 -0.6985) (xy 0.508 -1.7526) (xy -0.508 -1.7526)
				(xy -0.508 -0.6985) (xy -1.524 -0.6985) (xy -1.524 0.6985)
			)
			(stroke
				(width 0)
				(type default)
			)
			(fill no)
			(layer "F.CrtYd")
		)
		(fp_text user "S"
			(at 0.667258 2.328418 90)
			(unlocked yes)
			(layer "F.SilkS")
			(effects
				(font
					(size 0.635 0.4064)
					(thickness 0.1524)
				)
			)
		)
		(fp_text user "D"
			(at -0.360426 -2.460244 0)
			(unlocked yes)
			(layer "F.SilkS")
			(effects
				(font
					(size 0.635 0.4064)
					(thickness 0.1524)
				)
			)
		)
		(fp_text user "G"
			(at -1.618742 2.201418 90)
			(unlocked yes)
			(layer "F.SilkS")
			(effects
				(font
					(size 0.635 0.4064)
					(thickness 0.1524)
				)
			)
		)
		(pad "D" smd rect
			(at 0 -1.1176 180)
			(size 1.016 1.27)
			(layers "F.Cu" "F.Mask" "F.Paste")
			(net "PSU_DC_OK_N")
		)
		(pad "G" smd rect
			(at -1.016 1.1176 180)
			(size 1.016 1.27)
			(layers "F.Cu" "F.Mask" "F.Paste")
			(net "PSU5_DC_OK_R_BUF")
		)
		(pad "S" smd rect
			(at 1.016 1.1176 180)
			(size 1.016 1.27)
			(layers "F.Cu" "F.Mask" "F.Paste")
			(net "GND")
		)
	)
	(footprint ""
		(layer "F.Cu")
		(at 158.50616 -88.218772 -90)
		(property "Reference" "U33"
			(at -3.226816 0.69977 0)
			(unlocked yes)
			(layer "F.SilkS")
			(effects
				(font
					(size 0.7874 0.5842)
					(thickness 0.1524)
				)
				(justify left)
			)
		)
		(property "Value" ""
			(at 0 0 270)
			(layer "F.Fab")
			(effects
				(font
					(size 1.27 1.27)
				)
			)
		)
		(duplicate_pad_numbers_are_jumpers no)
		(fp_line
			(start -2.5146 1.4224)
			(end -2.5146 0.4572)
			(stroke
				(width 0.1524)
				(type default)
			)
			(layer "F.SilkS")
		)
		(fp_line
			(start 2.5146 1.4224)
			(end -2.5146 1.4224)
			(stroke
				(width 0.1524)
				(type default)
			)
			(layer "F.SilkS")
		)
		(fp_line
			(start -2.5146 0.4572)
			(end -2.0574 0)
			(stroke
				(width 0.1524)
				(type default)
			)
			(layer "F.SilkS")
		)
		(fp_line
			(start -2.0574 0)
			(end -2.5146 -0.4572)
			(stroke
				(width 0.1524)
				(type default)
			)
			(layer "F.SilkS")
		)
		(fp_line
			(start -2.5146 -0.4572)
			(end -2.5146 -1.4224)
			(stroke
				(width 0.1524)
				(type default)
			)
			(layer "F.SilkS")
		)
		(fp_line
			(start -2.5146 -1.4224)
			(end 2.5146 -1.4224)
			(stroke
				(width 0.1524)
				(type default)
			)
			(layer "F.SilkS")
		)
		(fp_line
			(start 2.5146 -1.4224)
			(end 2.5146 1.4224)
			(stroke
				(width 0.1524)
				(type default)
			)
			(layer "F.SilkS")
		)
		(fp_circle
			(center -1.905 0.889)
			(end -1.905 0.635)
			(stroke
				(width 0.1524)
				(type default)
			)
			(fill no)
			(layer "F.SilkS")
		)
		(fp_poly
			(pts
				(xy -2.1844 3.5052) (xy -2.1844 2.0066) (xy -2.5146 2.0066) (xy -2.5146 -2.0066) (xy -2.1844 -2.0066)
				(xy -2.1844 -3.5052) (xy 2.1844 -3.5052) (xy 2.1844 -2.0066) (xy 2.5146 -2.0066) (xy 2.5146 2.0066)
				(xy 2.1844 2.0066) (xy 2.1844 3.5052)
			)
			(stroke
				(width 0)
				(type default)
			)
			(fill no)
			(layer "F.CrtYd")
		)
		(pad "1" smd rect
			(at -1.905 2.6416 270)
			(size 0.5588 1.7272)
			(layers "F.Cu" "F.Mask" "F.Paste")
			(net "SPI_USB_NODE1_CSB_N")
		)
		(pad "2" smd rect
			(at -0.635 2.6416 270)
			(size 0.5588 1.7272)
			(layers "F.Cu" "F.Mask" "F.Paste")
			(net "SPI_USB_NODE1_SI_R")
		)
		(pad "3" smd rect
			(at 0.635 2.6416 270)
			(size 0.5588 1.7272)
			(layers "F.Cu" "F.Mask" "F.Paste")
			(net "SPI_USB_NODE1_WP_L")
		)
		(pad "4" smd rect
			(at 1.905 2.6416 270)
			(size 0.5588 1.7272)
			(layers "F.Cu" "F.Mask" "F.Paste")
			(net "GND")
		)
		(pad "5" smd rect
			(at 1.905 -2.6416 270)
			(size 0.5588 1.7272)
			(layers "F.Cu" "F.Mask" "F.Paste")
			(net "SPI_USB_NODE1_SO")
		)
		(pad "6" smd rect
			(at 0.635 -2.6416 270)
			(size 0.5588 1.7272)
			(layers "F.Cu" "F.Mask" "F.Paste")
			(net "SPI_USB_NODE1_CLK")
		)
		(pad "7" smd rect
			(at -0.635 -2.6416 270)
			(size 0.5588 1.7272)
			(layers "F.Cu" "F.Mask" "F.Paste")
			(net "SPI_USB_NODE1_HOLD_L")
		)
		(pad "8" smd rect
			(at -1.905 -2.6416 270)
			(size 0.5588 1.7272)
			(layers "F.Cu" "F.Mask" "F.Paste")
			(net "P3V3_NODE1")
		)
	)
	(footprint ""
		(layer "F.Cu")
		(at 4.725162 -155.788106 -90)
		(property "Reference" "R1310"
			(at -0.313436 -0.719328 0)
			(unlocked yes)
			(layer "F.SilkS")
			(effects
				(font
					(size 0.7874 0.5842)
					(thickness 0.1524)
				)
				(justify left)
			)
		)
		(property "Value" ""
			(at 0 0 270)
			(layer "F.Fab")
			(effects
				(font
					(size 1.27 1.27)
				)
			)
		)
		(duplicate_pad_numbers_are_jumpers no)
		(fp_line
			(start -0.7874 0.4064)
			(end -0.7874 -0.4064)
			(stroke
				(width 0.1524)
				(type default)
			)
			(layer "F.SilkS")
		)
		(fp_line
			(start 0.7874 0.4064)
			(end -0.7874 0.4064)
			(stroke
				(width 0.1524)
				(type default)
			)
			(layer "F.SilkS")
		)
		(fp_line
			(start -0.7874 -0.4064)
			(end 0.7874 -0.4064)
			(stroke
				(width 0.1524)
				(type default)
			)
			(layer "F.SilkS")
		)
		(fp_line
			(start 0.7874 -0.4064)
			(end 0.7874 0.4064)
			(stroke
				(width 0.1524)
				(type default)
			)
			(layer "F.SilkS")
		)
		(fp_poly
			(pts
				(xy -0.508 0.2794) (xy -0.508 0.2286) (xy -0.635 0.2286) (xy -0.635 -0.254) (xy -0.5334 -0.254)
				(xy -0.5334 -0.2794) (xy 0.5334 -0.2794) (xy 0.5334 -0.254) (xy 0.635 -0.254) (xy 0.635 0.254) (xy 0.5334 0.254)
				(xy 0.5334 0.2794)
			)
			(stroke
				(width 0)
				(type default)
			)
			(fill no)
			(layer "F.CrtYd")
		)
		(pad "1" smd rect
			(at 0.40005 0 270)
			(size 0.4572 0.508)
			(layers "F.Cu" "F.Mask" "F.Paste")
			(net "P3V3_NODE1")
		)
		(pad "2" smd rect
			(at -0.40005 0 270)
			(size 0.4572 0.508)
			(layers "F.Cu" "F.Mask" "F.Paste")
			(net "UART_RI_P5_LS_N")
		)
	)
	(footprint ""
		(layer "F.Cu")
		(at 23.736554 -100.067872 180)
		(property "Reference" "U134"
			(at 1.318514 4.418076 0)
			(unlocked yes)
			(layer "F.SilkS")
			(effects
				(font
					(size 0.7874 0.5842)
					(thickness 0.1524)
				)
				(justify left)
			)
		)
		(property "Value" ""
			(at 0 0 180)
			(layer "F.Fab")
			(effects
				(font
					(size 1.27 1.27)
				)
			)
		)
		(duplicate_pad_numbers_are_jumpers no)
		(fp_line
			(start 2.5146 1.4224)
			(end -2.5146 1.4224)
			(stroke
				(width 0.1524)
				(type default)
			)
			(layer "F.SilkS")
		)
		(fp_line
			(start 2.5146 -1.4224)
			(end 2.5146 1.4224)
			(stroke
				(width 0.1524)
				(type default)
			)
			(layer "F.SilkS")
		)
		(fp_line
			(start -2.0574 0)
			(end -2.5146 -0.4572)
			(stroke
				(width 0.1524)
				(type default)
			)
			(layer "F.SilkS")
		)
		(fp_line
			(start -2.5146 1.4224)
			(end -2.5146 0.4572)
			(stroke
				(width 0.1524)
				(type default)
			)
			(layer "F.SilkS")
		)
		(fp_line
			(start -2.5146 0.4572)
			(end -2.0574 0)
			(stroke
				(width 0.1524)
				(type default)
			)
			(layer "F.SilkS")
		)
		(fp_line
			(start -2.5146 -0.4572)
			(end -2.5146 -1.4224)
			(stroke
				(width 0.1524)
				(type default)
			)
			(layer "F.SilkS")
		)
		(fp_line
			(start -2.5146 -1.4224)
			(end 2.5146 -1.4224)
			(stroke
				(width 0.1524)
				(type default)
			)
			(layer "F.SilkS")
		)
		(fp_circle
			(center -1.905 0.889)
			(end -2.159 0.889)
			(stroke
				(width 0.1524)
				(type default)
			)
			(fill no)
			(layer "F.SilkS")
		)
		(fp_poly
			(pts
				(xy -2.1844 3.5052) (xy -2.1844 2.0066) (xy -2.5146 2.0066) (xy -2.5146 -2.0066) (xy -2.1844 -2.0066)
				(xy -2.1844 -3.5052) (xy 2.1844 -3.5052) (xy 2.1844 -2.0066) (xy 2.5146 -2.0066) (xy 2.5146 2.0066)
				(xy 2.1844 2.0066) (xy 2.1844 3.5052)
			)
			(stroke
				(width 0)
				(type default)
			)
			(fill no)
			(layer "F.CrtYd")
		)
		(pad "1" smd rect
			(at -1.905 2.6416 180)
			(size 0.5588 1.7272)
			(layers "F.Cu" "F.Mask" "F.Paste")
			(net "FRU_SYS_A0")
		)
		(pad "2" smd rect
			(at -0.635 2.6416 180)
			(size 0.5588 1.7272)
			(layers "F.Cu" "F.Mask" "F.Paste")
			(net "FRU_SYS_A1")
		)
		(pad "3" smd rect
			(at 0.635 2.6416 180)
			(size 0.5588 1.7272)
			(layers "F.Cu" "F.Mask" "F.Paste")
			(net "FRU_SYS_A2")
		)
		(pad "4" smd rect
			(at 1.905 2.6416 180)
			(size 0.5588 1.7272)
			(layers "F.Cu" "F.Mask" "F.Paste")
			(net "GND")
		)
		(pad "5" smd rect
			(at 1.905 -2.6416 180)
			(size 0.5588 1.7272)
			(layers "F.Cu" "F.Mask" "F.Paste")
			(net "SMB_MUX_CPU_ICS_NODE1_DAT")
		)
		(pad "6" smd rect
			(at 0.635 -2.6416 180)
			(size 0.5588 1.7272)
			(layers "F.Cu" "F.Mask" "F.Paste")
			(net "SMB_MUX_CPU_ICS_NODE1_CLK")
		)
		(pad "7" smd rect
			(at -0.635 -2.6416 180)
			(size 0.5588 1.7272)
			(layers "F.Cu" "F.Mask" "F.Paste")
			(net "N43448372")
		)
		(pad "8" smd rect
			(at -1.905 -2.6416 180)
			(size 0.5588 1.7272)
			(layers "F.Cu" "F.Mask" "F.Paste")
			(net "P3V3_NODE1")
		)
	)
	(footprint ""
		(layer "F.Cu")
		(at 47.215298 -176.247298)
		(property "Reference" "R1012"
			(at -0.007366 132.939282 0)
			(unlocked yes)
			(layer "F.SilkS")
			(effects
				(font
					(size 0.7874 0.5842)
					(thickness 0.1524)
				)
				(justify left)
			)
		)
		(property "Value" ""
			(at 0 0 0)
			(layer "F.Fab")
			(effects
				(font
					(size 1.27 1.27)
				)
			)
		)
		(duplicate_pad_numbers_are_jumpers no)
		(fp_line
			(start -0.7874 -0.4064)
			(end 0.7874 -0.4064)
			(stroke
				(width 0.1524)
				(type default)
			)
			(layer "F.SilkS")
		)
		(fp_line
			(start -0.7874 0.4064)
			(end -0.7874 -0.4064)
			(stroke
				(width 0.1524)
				(type default)
			)
			(layer "F.SilkS")
		)
		(fp_line
			(start 0.7874 -0.4064)
			(end 0.7874 0.4064)
			(stroke
				(width 0.1524)
				(type default)
			)
			(layer "F.SilkS")
		)
		(fp_line
			(start 0.7874 0.4064)
			(end -0.7874 0.4064)
			(stroke
				(width 0.1524)
				(type default)
			)
			(layer "F.SilkS")
		)
		(fp_poly
			(pts
				(xy -0.508 0.2794) (xy -0.508 0.2286) (xy -0.635 0.2286) (xy -0.635 -0.254) (xy -0.5334 -0.254)
				(xy -0.5334 -0.2794) (xy 0.5334 -0.2794) (xy 0.5334 -0.254) (xy 0.635 -0.254) (xy 0.635 0.254) (xy 0.5334 0.254)
				(xy 0.5334 0.2794)
			)
			(stroke
				(width 0)
				(type default)
			)
			(fill no)
			(layer "F.CrtYd")
		)
		(pad "1" smd rect
			(at 0.40005 0)
			(size 0.4572 0.508)
			(layers "F.Cu" "F.Mask" "F.Paste")
			(net "PSU_DC_OK_N")
		)
		(pad "2" smd rect
			(at -0.40005 0)
			(size 0.4572 0.508)
			(layers "F.Cu" "F.Mask" "F.Paste")
			(net "P12V_PDB")
		)
	)
	(footprint ""
		(layer "F.Cu")
		(at 77.96276 -188.126624 -90)
		(property "Reference" "R932"
			(at -4.548886 1.495298 90)
			(unlocked yes)
			(layer "F.SilkS")
			(effects
				(font
					(size 0.7874 0.5842)
					(thickness 0.1524)
				)
				(justify left)
			)
		)
		(property "Value" ""
			(at 0 0 270)
			(layer "F.Fab")
			(effects
				(font
					(size 1.27 1.27)
				)
			)
		)
		(duplicate_pad_numbers_are_jumpers no)
		(fp_line
			(start -0.7874 0.4064)
			(end -0.7874 -0.4064)
			(stroke
				(width 0.1524)
				(type default)
			)
			(layer "F.SilkS")
		)
		(fp_line
			(start 0.7874 0.4064)
			(end -0.7874 0.4064)
			(stroke
				(width 0.1524)
				(type default)
			)
			(layer "F.SilkS")
		)
		(fp_line
			(start -0.7874 -0.4064)
			(end 0.7874 -0.4064)
			(stroke
				(width 0.1524)
				(type default)
			)
			(layer "F.SilkS")
		)
		(fp_line
			(start 0.7874 -0.4064)
			(end 0.7874 0.4064)
			(stroke
				(width 0.1524)
				(type default)
			)
			(layer "F.SilkS")
		)
		(fp_poly
			(pts
				(xy -0.508 0.2794) (xy -0.508 0.2286) (xy -0.635 0.2286) (xy -0.635 -0.254) (xy -0.5334 -0.254)
				(xy -0.5334 -0.2794) (xy 0.5334 -0.2794) (xy 0.5334 -0.254) (xy 0.635 -0.254) (xy 0.635 0.254) (xy 0.5334 0.254)
				(xy 0.5334 0.2794)
			)
			(stroke
				(width 0)
				(type default)
			)
			(fill no)
			(layer "F.CrtYd")
		)
		(pad "1" smd rect
			(at 0.40005 0 270)
			(size 0.4572 0.508)
			(layers "F.Cu" "F.Mask" "F.Paste")
			(net "UART_T4_NODE1_RXD")
		)
		(pad "2" smd rect
			(at -0.40005 0 270)
			(size 0.4572 0.508)
			(layers "F.Cu" "F.Mask" "F.Paste")
			(net "UART_T4_NODE1_RXD_R")
		)
	)
)
